(kicad_pcb
	(version 20260206)
	(generator "pcbnew")
	(generator_version "10.0")
	(general
		(thickness 1.6)
		(legacy_teardrops no)
	)
	(paper "A4")
	(title_block
		(title "12092022_DA0F0TFB6D0_F0T_FAN_BOARD_MP5048_D_brd_v02_OCP.brd")
		(comment 1 "Grand Teton / footprints 727-730 of 924")
	)
	(layers
		(0 "F.Cu" signal "TOP")
		(4 "In1.Cu" signal "GND")
		(6 "In2.Cu" signal "IN1")
		(8 "In3.Cu" signal "IN2")
		(10 "In4.Cu" signal "GND1")
		(2 "B.Cu" signal "BOTTOM")
		(9 "F.Adhes" user "F.Adhesive")
		(11 "B.Adhes" user "B.Adhesive")
		(13 "F.Paste" user "Package Geometry/Pastemask Top")
		(15 "B.Paste" user "Package Geometry/Pastemask Bottom")
		(5 "F.SilkS" user "Ref Des/Silkscreen Top")
		(7 "B.SilkS" user "Ref Des/Silkscreen Bottom")
		(1 "F.Mask" user "Board Geometry/Soldermask Top")
		(3 "B.Mask" user "Board Geometry/Soldermask Bottom")
		(17 "Dwgs.User" user "User.Drawings")
		(19 "Cmts.User" user "User.Comments")
		(21 "Eco1.User" user "User.Eco1")
		(23 "Eco2.User" user "User.Eco2")
		(25 "Edge.Cuts" user "Board Geometry/Outline")
		(27 "Margin" user)
		(31 "F.CrtYd" user "Package Geometry/Place Bound Top")
		(29 "B.CrtYd" user "Package Geometry/Place Bound Bottom")
		(35 "F.Fab" user "Ref Des/Assembly Top")
		(33 "B.Fab" user "Ref Des/Assembly Bottom")
	)
	(footprint ""
		(layer "B.Cu")
		(at 37.31768 -58.995056)
		(property "Reference" "PU3"
			(at 5.22732 2.252726 0)
			(unlocked yes)
			(layer "B.SilkS")
			(effects
				(font
					(size 0.7874 0.5842)
					(thickness 0.1524)
				)
				(justify left mirror)
			)
		)
		(property "Value" ""
			(at 0 0 0)
			(layer "B.Fab")
			(effects
				(font
					(size 1.27 1.27)
				)
				(justify mirror)
			)
		)
		(duplicate_pad_numbers_are_jumpers no)
		(fp_line
			(start -2.549906 -2.549906)
			(end -2.4384 -2.549906)
			(stroke
				(width 0.1524)
				(type default)
			)
			(layer "B.SilkS")
		)
		(fp_line
			(start -2.549906 -2.2352)
			(end -2.549906 -2.549906)
			(stroke
				(width 0.1524)
				(type default)
			)
			(layer "B.SilkS")
		)
		(fp_line
			(start -2.549906 -1.4986)
			(end -2.549906 -1.7526)
			(stroke
				(width 0.1524)
				(type default)
			)
			(layer "B.SilkS")
		)
		(fp_line
			(start -2.549906 -0.6858)
			(end -2.549906 -0.9144)
			(stroke
				(width 0.1524)
				(type default)
			)
			(layer "B.SilkS")
		)
		(fp_line
			(start -2.549906 0.9144)
			(end -2.549906 -0.1016)
			(stroke
				(width 0.1524)
				(type default)
			)
			(layer "B.SilkS")
		)
		(fp_line
			(start -2.549906 1.7526)
			(end -2.549906 1.4986)
			(stroke
				(width 0.1524)
				(type default)
			)
			(layer "B.SilkS")
		)
		(fp_line
			(start -2.549906 2.549906)
			(end -2.549906 2.2352)
			(stroke
				(width 0.1524)
				(type default)
			)
			(layer "B.SilkS")
		)
		(fp_line
			(start -2.4384 2.549906)
			(end -2.549906 2.549906)
			(stroke
				(width 0.1524)
				(type default)
			)
			(layer "B.SilkS")
		)
		(fp_line
			(start -2.199894 2.9464)
			(end -2.199894 3.4544)
			(stroke
				(width 0.1524)
				(type default)
			)
			(layer "B.SilkS")
		)
		(fp_line
			(start -1.800098 -3.9624)
			(end -1.800098 -2.9464)
			(stroke
				(width 0.1524)
				(type default)
			)
			(layer "B.SilkS")
		)
		(fp_line
			(start -0.199898 2.9464)
			(end -0.199898 3.9624)
			(stroke
				(width 0.1524)
				(type default)
			)
			(layer "B.SilkS")
		)
		(fp_line
			(start 0.199898 -3.4544)
			(end 0.199898 -2.9464)
			(stroke
				(width 0.1524)
				(type default)
			)
			(layer "B.SilkS")
		)
		(fp_line
			(start 1.800098 2.9464)
			(end 1.800098 3.4544)
			(stroke
				(width 0.1524)
				(type default)
			)
			(layer "B.SilkS")
		)
		(fp_line
			(start 2.199894 -3.9624)
			(end 2.199894 -2.9464)
			(stroke
				(width 0.1524)
				(type default)
			)
			(layer "B.SilkS")
		)
		(fp_line
			(start 2.4384 -2.549906)
			(end 2.549906 -2.549906)
			(stroke
				(width 0.1524)
				(type default)
			)
			(layer "B.SilkS")
		)
		(fp_line
			(start 2.549906 -2.549906)
			(end 2.549906 -2.2352)
			(stroke
				(width 0.1524)
				(type default)
			)
			(layer "B.SilkS")
		)
		(fp_line
			(start 2.549906 -1.7526)
			(end 2.549906 -1.4986)
			(stroke
				(width 0.1524)
				(type default)
			)
			(layer "B.SilkS")
		)
		(fp_line
			(start 2.549906 -0.9144)
			(end 2.549906 0.1016)
			(stroke
				(width 0.1524)
				(type default)
			)
			(layer "B.SilkS")
		)
		(fp_line
			(start 2.549906 0.6858)
			(end 2.549906 0.9144)
			(stroke
				(width 0.1524)
				(type default)
			)
			(layer "B.SilkS")
		)
		(fp_line
			(start 2.549906 1.4986)
			(end 2.549906 1.7526)
			(stroke
				(width 0.1524)
				(type default)
			)
			(layer "B.SilkS")
		)
		(fp_line
			(start 2.549906 2.2352)
			(end 2.549906 2.549906)
			(stroke
				(width 0.1524)
				(type default)
			)
			(layer "B.SilkS")
		)
		(fp_line
			(start 2.549906 2.549906)
			(end 2.4384 2.549906)
			(stroke
				(width 0.1524)
				(type default)
			)
			(layer "B.SilkS")
		)
		(fp_poly
			(pts
				(xy 3.7084 -1.584706) (xy 2.939034 -1.199896) (xy 3.7084 -0.81534)
			)
			(stroke
				(width 0)
				(type default)
			)
			(fill yes)
			(layer "B.SilkS")
		)
		(fp_line
			(start -2.549906 -2.549906)
			(end 2.549906 -2.549906)
			(stroke
				(width 0.1)
				(type default)
			)
			(layer "B.Fab")
		)
		(fp_line
			(start -2.549906 2.549906)
			(end -2.549906 -2.549906)
			(stroke
				(width 0.1)
				(type default)
			)
			(layer "B.Fab")
		)
		(fp_line
			(start -2.199894 2.9464)
			(end -2.199894 3.4544)
			(stroke
				(width 0.1)
				(type default)
			)
			(layer "B.Fab")
		)
		(fp_line
			(start -1.800098 -3.9624)
			(end -1.800098 -2.9464)
			(stroke
				(width 0.1)
				(type default)
			)
			(layer "B.Fab")
		)
		(fp_line
			(start -0.199898 2.9464)
			(end -0.199898 3.9624)
			(stroke
				(width 0.1)
				(type default)
			)
			(layer "B.Fab")
		)
		(fp_line
			(start 0.199898 -3.4544)
			(end 0.199898 -2.9464)
			(stroke
				(width 0.1)
				(type default)
			)
			(layer "B.Fab")
		)
		(fp_line
			(start 1.800098 2.9464)
			(end 1.800098 3.4544)
			(stroke
				(width 0.1)
				(type default)
			)
			(layer "B.Fab")
		)
		(fp_line
			(start 2.199894 -3.9624)
			(end 2.199894 -2.9464)
			(stroke
				(width 0.1)
				(type default)
			)
			(layer "B.Fab")
		)
		(fp_line
			(start 2.549906 -2.549906)
			(end 2.549906 2.549906)
			(stroke
				(width 0.1)
				(type default)
			)
			(layer "B.Fab")
		)
		(fp_line
			(start 2.549906 2.549906)
			(end -2.549906 2.549906)
			(stroke
				(width 0.1)
				(type default)
			)
			(layer "B.Fab")
		)
		(fp_poly
			(pts
				(xy 3.7084 -1.584706) (xy 2.939034 -1.199896) (xy 3.7084 -0.81534)
			)
			(stroke
				(width 0)
				(type default)
			)
			(fill yes)
			(layer "B.Fab")
		)
		(fp_text user "16"
			(at -3.329432 1.2192 270)
			(unlocked yes)
			(layer "B.SilkS")
			(effects
				(font
					(size 0.635 0.4064)
					(thickness 0.1524)
				)
				(justify mirror)
			)
		)
		(fp_text user "18"
			(at -3.304032 -1.2192 270)
			(unlocked yes)
			(layer "B.SilkS")
			(effects
				(font
					(size 0.635 0.4064)
					(thickness 0.1524)
				)
				(justify mirror)
			)
		)
		(fp_text user "15"
			(at -2.8956 3.126232 0)
			(unlocked yes)
			(layer "B.SilkS")
			(effects
				(font
					(size 0.635 0.4064)
					(thickness 0.1524)
				)
				(justify mirror)
			)
		)
		(fp_text user "19"
			(at -2.8448 -3.096768 0)
			(unlocked yes)
			(layer "B.SilkS")
			(effects
				(font
					(size 0.635 0.4064)
					(thickness 0.1524)
				)
				(justify mirror)
			)
		)
		(fp_text user "4"
			(at 2.6416 3.151632 0)
			(unlocked yes)
			(layer "B.SilkS")
			(effects
				(font
					(size 0.635 0.4064)
					(thickness 0.1524)
				)
				(justify mirror)
			)
		)
		(fp_text user "30"
			(at 2.9464 -3.045968 0)
			(unlocked yes)
			(layer "B.SilkS")
			(effects
				(font
					(size 0.635 0.4064)
					(thickness 0.1524)
				)
				(justify mirror)
			)
		)
		(fp_text user "3"
			(at 3.299968 1.1938 270)
			(unlocked yes)
			(layer "B.SilkS")
			(effects
				(font
					(size 0.635 0.4064)
					(thickness 0.1524)
				)
				(justify mirror)
			)
		)
		(fp_text user "16"
			(at -3.329432 1.2192 270)
			(unlocked yes)
			(layer "B.Fab")
			(effects
				(font
					(size 0.635 0.4064)
					(thickness 0.1524)
				)
				(justify mirror)
			)
		)
		(fp_text user "18"
			(at -3.304032 -1.2192 270)
			(unlocked yes)
			(layer "B.Fab")
			(effects
				(font
					(size 0.635 0.4064)
					(thickness 0.1524)
				)
				(justify mirror)
			)
		)
		(fp_text user "15"
			(at -2.8956 3.126232 0)
			(unlocked yes)
			(layer "B.Fab")
			(effects
				(font
					(size 0.635 0.4064)
					(thickness 0.1524)
				)
				(justify mirror)
			)
		)
		(fp_text user "19"
			(at -2.8448 -3.096768 0)
			(unlocked yes)
			(layer "B.Fab")
			(effects
				(font
					(size 0.635 0.4064)
					(thickness 0.1524)
				)
				(justify mirror)
			)
		)
		(fp_text user "4"
			(at 2.6416 3.151632 0)
			(unlocked yes)
			(layer "B.Fab")
			(effects
				(font
					(size 0.635 0.4064)
					(thickness 0.1524)
				)
				(justify mirror)
			)
		)
		(fp_text user "30"
			(at 2.9464 -3.045968 0)
			(unlocked yes)
			(layer "B.Fab")
			(effects
				(font
					(size 0.635 0.4064)
					(thickness 0.1524)
				)
				(justify mirror)
			)
		)
		(fp_text user "3"
			(at 3.299968 1.1938 270)
			(unlocked yes)
			(layer "B.Fab")
			(effects
				(font
					(size 0.635 0.4064)
					(thickness 0.1524)
				)
				(justify mirror)
			)
		)
		(pad "1" smd circle
			(at 1.599946 -1.199896 270)
			(size 0 0)
			(layers "B.Cu" "B.Mask" "B.Paste")
			(net "P52V_HSC")
		)
		(pad "2" smd rect
			(at 1.549908 0.40005 90)
			(size 0.3048 2.5146)
			(layers "B.Cu" "B.Mask" "B.Paste")
			(net "P52V_HSC")
		)
		(pad "3" smd rect
			(at 1.549908 1.199896 90)
			(size 0.3048 2.5146)
			(layers "B.Cu" "B.Mask" "B.Paste")
			(net "P52V_FAN_3")
		)
		(pad "4" smd circle
			(at 2.199894 2.350008)
			(size 0 0)
			(layers "B.Cu" "B.Mask" "B.Paste")
			(net "P52V_FAN_3")
		)
		(pad "5" smd rect
			(at 1.800098 2.350008 180)
			(size 0.1778 0.9144)
			(layers "B.Cu" "B.Mask" "B.Paste")
			(net "P52V_FAN_3")
		)
		(pad "6" smd rect
			(at 1.400048 2.350008 180)
			(size 0.1778 0.9144)
			(layers "B.Cu" "B.Mask" "B.Paste")
			(net "P52V_FAN_3")
		)
		(pad "7" smd rect
			(at 0.999998 2.350008 180)
			(size 0.1778 0.9144)
			(layers "B.Cu" "B.Mask" "B.Paste")
			(net "P52V_FAN_3")
		)
		(pad "8" smd rect
			(at 0.599948 2.350008 180)
			(size 0.1778 0.9144)
			(layers "B.Cu" "B.Mask" "B.Paste")
			(net "P52V_FAN_3")
		)
		(pad "9" smd rect
			(at 0.199898 2.350008 180)
			(size 0.1778 0.9144)
			(layers "B.Cu" "B.Mask" "B.Paste")
			(net "P52V_FAN_3")
		)
		(pad "10" smd rect
			(at -0.199898 2.350008 180)
			(size 0.1778 0.9144)
			(layers "B.Cu" "B.Mask" "B.Paste")
			(net "P52V_FAN_3")
		)
		(pad "11" smd rect
			(at -0.599948 2.350008 180)
			(size 0.1778 0.9144)
			(layers "B.Cu" "B.Mask" "B.Paste")
			(net "P52V_FAN_3")
		)
		(pad "12" smd rect
			(at -0.999998 2.350008 180)
			(size 0.1778 0.9144)
			(layers "B.Cu" "B.Mask" "B.Paste")
			(net "P52V_FAN_3")
		)
		(pad "13" smd rect
			(at -1.400048 2.350008 180)
			(size 0.1778 0.9144)
			(layers "B.Cu" "B.Mask" "B.Paste")
			(net "P52V_FAN_3")
		)
		(pad "14" smd rect
			(at -1.800098 2.350008 180)
			(size 0.1778 0.9144)
			(layers "B.Cu" "B.Mask" "B.Paste")
			(net "P52V_FAN_3")
		)
		(pad "15" smd circle
			(at -2.199894 2.350008)
			(size 0 0)
			(layers "B.Cu" "B.Mask" "B.Paste")
			(net "P52V_FAN_3")
		)
		(pad "16" smd rect
			(at -1.549908 1.199896 90)
			(size 0.3048 2.5146)
			(layers "B.Cu" "B.Mask" "B.Paste")
			(net "P52V_FAN_3")
		)
		(pad "17" smd rect
			(at -1.549908 -0.40005 90)
			(size 0.3048 2.5146)
			(layers "B.Cu" "B.Mask" "B.Paste")
			(net "P52V_FAN_3")
		)
		(pad "18" smd rect
			(at -1.549908 -1.199896 90)
			(size 0.3048 2.5146)
			(layers "B.Cu" "B.Mask" "B.Paste")
			(net "P52V_HSC")
		)
		(pad "19" smd circle
			(at -2.199894 -2.350008 180)
			(size 0 0)
			(layers "B.Cu" "B.Mask" "B.Paste")
			(net "FAN_3_CS")
		)
		(pad "20" smd rect
			(at -1.800098 -2.350008 180)
			(size 0.1778 0.9144)
			(layers "B.Cu" "B.Mask" "B.Paste")
			(net "FAN_3_IMON")
		)
		(pad "21" smd rect
			(at -1.400048 -2.350008 180)
			(size 0.1778 0.9144)
			(layers "B.Cu" "B.Mask" "B.Paste")
			(net "FAN_3_SS")
		)
		(pad "22" smd rect
			(at -0.999998 -2.350008 180)
			(size 0.1778 0.9144)
			(layers "B.Cu" "B.Mask" "B.Paste")
			(net "FAN_3_FAULT")
		)
		(pad "23" smd rect
			(at -0.599948 -2.350008 180)
			(size 0.1778 0.9144)
			(layers "B.Cu" "B.Mask" "B.Paste")
			(net "FAN_3_TIMER")
		)
		(pad "24" smd rect
			(at -0.199898 -2.350008 180)
			(size 0.1778 0.9144)
			(layers "B.Cu" "B.Mask" "B.Paste")
			(net "FAN_3_CLREF")
		)
		(pad "25" smd rect
			(at 0.199898 -2.350008 180)
			(size 0.1778 0.9144)
			(layers "B.Cu" "B.Mask" "B.Paste")
			(net "GND")
		)
		(pad "26" smd rect
			(at 0.599948 -2.350008 180)
			(size 0.1778 0.9144)
			(layers "B.Cu" "B.Mask" "B.Paste")
			(net "FAN_3_ON")
		)
		(pad "27" smd rect
			(at 0.999998 -2.350008 180)
			(size 0.1778 0.9144)
			(layers "B.Cu" "B.Mask" "B.Paste")
			(net "FAN_3_P3V_R")
		)
		(pad "28" smd rect
			(at 1.400048 -2.350008 180)
			(size 0.1778 0.9144)
			(layers "B.Cu" "B.Mask" "B.Paste")
			(net "FAN_3_P5V")
		)
		(pad "29" smd rect
			(at 1.800098 -2.350008 180)
			(size 0.1778 0.9144)
			(layers "B.Cu" "B.Mask" "B.Paste")
			(net "FAN_3_TEMP")
		)
		(pad "30" smd circle
			(at 2.199894 -2.350008 180)
			(size 0 0)
			(layers "B.Cu" "B.Mask" "B.Paste")
			(net "FAN_3_MODE")
		)
	)
	(footprint ""
		(layer "B.Cu")
		(at 35.1536 -88.399112)
		(property "Reference" "C2102"
			(at 0 0 0)
			(layer "B.SilkS")
			(hide yes)
			(effects
				(font
					(size 1.27 1.27)
				)
				(justify mirror)
			)
		)
		(property "Value" ""
			(at 0 0 0)
			(layer "B.Fab")
			(effects
				(font
					(size 1.27 1.27)
				)
				(justify mirror)
			)
		)
		(duplicate_pad_numbers_are_jumpers no)
		(fp_line
			(start -2.2098 -0.9398)
			(end -2.2098 0.9398)
			(stroke
				(width 0.1524)
				(type default)
			)
			(layer "B.SilkS")
		)
		(fp_line
			(start -2.2098 0.9398)
			(end 2.2098 0.9398)
			(stroke
				(width 0.1524)
				(type default)
			)
			(layer "B.SilkS")
		)
		(fp_line
			(start 2.2098 -0.9398)
			(end -2.2098 -0.9398)
			(stroke
				(width 0.1524)
				(type default)
			)
			(layer "B.SilkS")
		)
		(fp_line
			(start 2.2098 0.9398)
			(end 2.2098 -0.9398)
			(stroke
				(width 0.1524)
				(type default)
			)
			(layer "B.SilkS")
		)
		(fp_line
			(start -1.700022 -0.899922)
			(end -1.700022 0.899922)
			(stroke
				(width 0.1)
				(type default)
			)
			(layer "B.Fab")
		)
		(fp_line
			(start -1.700022 0.899922)
			(end 1.700022 0.899922)
			(stroke
				(width 0.1)
				(type default)
			)
			(layer "B.Fab")
		)
		(fp_line
			(start 1.700022 -0.899922)
			(end -1.700022 -0.899922)
			(stroke
				(width 0.1)
				(type default)
			)
			(layer "B.Fab")
		)
		(fp_line
			(start 1.700022 0.899922)
			(end 1.700022 -0.899922)
			(stroke
				(width 0.1)
				(type default)
			)
			(layer "B.Fab")
		)
		(pad "1" smd rect
			(at 1.4732 0)
			(size 1.1684 1.5748)
			(layers "B.Cu" "B.Mask" "B.Paste")
			(net "P52V_FAN_2")
		)
		(pad "2" smd rect
			(at -1.4732 0)
			(size 1.1684 1.5748)
			(layers "B.Cu" "B.Mask" "B.Paste")
			(net "GND")
		)
	)
	(footprint ""
		(layer "B.Cu")
		(at 34.163 -250.23699 -90)
		(property "Reference" "PC27"
			(at 0 0 90)
			(layer "B.SilkS")
			(hide yes)
			(effects
				(font
					(size 1.27 1.27)
				)
				(justify mirror)
			)
		)
		(property "Value" ""
			(at 0 0 90)
			(layer "B.Fab")
			(effects
				(font
					(size 1.27 1.27)
				)
				(justify mirror)
			)
		)
		(duplicate_pad_numbers_are_jumpers no)
		(fp_line
			(start -0.7874 0.4064)
			(end 0.7874 0.4064)
			(stroke
				(width 0.1524)
				(type default)
			)
			(layer "B.SilkS")
		)
		(fp_line
			(start 0.7874 0.4064)
			(end 0.7874 -0.4064)
			(stroke
				(width 0.1524)
				(type default)
			)
			(layer "B.SilkS")
		)
		(fp_line
			(start -0.7874 -0.4064)
			(end -0.7874 0.4064)
			(stroke
				(width 0.1524)
				(type default)
			)
			(layer "B.SilkS")
		)
		(fp_line
			(start 0.7874 -0.4064)
			(end -0.7874 -0.4064)
			(stroke
				(width 0.1524)
				(type default)
			)
			(layer "B.SilkS")
		)
		(fp_line
			(start -0.67945 0.3048)
			(end -0.120396 0.3048)
			(stroke
				(width 0.1)
				(type default)
			)
			(layer "B.Fab")
		)
		(fp_line
			(start -0.120396 0.3048)
			(end -0.120396 0.2794)
			(stroke
				(width 0.1)
				(type default)
			)
			(layer "B.Fab")
		)
		(fp_line
			(start 0.12065 0.3048)
			(end 0.67945 0.3048)
			(stroke
				(width 0.1)
				(type default)
			)
			(layer "B.Fab")
		)
		(fp_line
			(start 0.67945 0.3048)
			(end 0.67945 -0.305054)
			(stroke
				(width 0.1)
				(type default)
			)
			(layer "B.Fab")
		)
		(fp_line
			(start -0.120396 0.2794)
			(end 0.12065 0.2794)
			(stroke
				(width 0.1)
				(type default)
			)
			(layer "B.Fab")
		)
		(fp_line
			(start 0.12065 0.2794)
			(end 0.12065 0.3048)
			(stroke
				(width 0.1)
				(type default)
			)
			(layer "B.Fab")
		)
		(fp_line
			(start -0.12065 -0.2794)
			(end -0.12065 -0.3048)
			(stroke
				(width 0.1)
				(type default)
			)
			(layer "B.Fab")
		)
		(fp_line
			(start 0.12065 -0.2794)
			(end -0.12065 -0.2794)
			(stroke
				(width 0.1)
				(type default)
			)
			(layer "B.Fab")
		)
		(fp_line
			(start -0.67945 -0.3048)
			(end -0.67945 0.3048)
			(stroke
				(width 0.1)
				(type default)
			)
			(layer "B.Fab")
		)
		(fp_line
			(start -0.12065 -0.3048)
			(end -0.67945 -0.3048)
			(stroke
				(width 0.1)
				(type default)
			)
			(layer "B.Fab")
		)
		(fp_line
			(start 0.12065 -0.305054)
			(end 0.12065 -0.2794)
			(stroke
				(width 0.1)
				(type default)
			)
			(layer "B.Fab")
		)
		(fp_line
			(start 0.67945 -0.305054)
			(end 0.12065 -0.305054)
			(stroke
				(width 0.1)
				(type default)
			)
			(layer "B.Fab")
		)
		(pad "1" smd circle
			(at 0.40005 0 90)
			(size 0 0)
			(layers "B.Cu" "B.Mask" "B.Paste")
			(net "FAN_1_SS")
		)
		(pad "2" smd circle
			(at -0.40005 0 90)
			(size 0 0)
			(layers "B.Cu" "B.Mask" "B.Paste")
			(net "GND")
		)
	)
	(footprint ""
		(layer "B.Cu")
		(at 35.1536 -90.939112)
		(property "Reference" "C2104"
			(at 0 0 0)
			(layer "B.SilkS")
			(hide yes)
			(effects
				(font
					(size 1.27 1.27)
				)
				(justify mirror)
			)
		)
		(property "Value" ""
			(at 0 0 0)
			(layer "B.Fab")
			(effects
				(font
					(size 1.27 1.27)
				)
				(justify mirror)
			)
		)
		(duplicate_pad_numbers_are_jumpers no)
		(fp_line
			(start -2.2098 -0.9398)
			(end -2.2098 0.9398)
			(stroke
				(width 0.1524)
				(type default)
			)
			(layer "B.SilkS")
		)
		(fp_line
			(start -2.2098 0.9398)
			(end 2.2098 0.9398)
			(stroke
				(width 0.1524)
				(type default)
			)
			(layer "B.SilkS")
		)
		(fp_line
			(start 2.2098 -0.9398)
			(end -2.2098 -0.9398)
			(stroke
				(width 0.1524)
				(type default)
			)
			(layer "B.SilkS")
		)
		(fp_line
			(start 2.2098 0.9398)
			(end 2.2098 -0.9398)
			(stroke
				(width 0.1524)
				(type default)
			)
			(layer "B.SilkS")
		)
		(fp_line
			(start -1.700022 -0.899922)
			(end -1.700022 0.899922)
			(stroke
				(width 0.1)
				(type default)
			)
			(layer "B.Fab")
		)
		(fp_line
			(start -1.700022 0.899922)
			(end 1.700022 0.899922)
			(stroke
				(width 0.1)
				(type default)
			)
			(layer "B.Fab")
		)
		(fp_line
			(start 1.700022 -0.899922)
			(end -1.700022 -0.899922)
			(stroke
				(width 0.1)
				(type default)
			)
			(layer "B.Fab")
		)
		(fp_line
			(start 1.700022 0.899922)
			(end 1.700022 -0.899922)
			(stroke
				(width 0.1)
				(type default)
			)
			(layer "B.Fab")
		)
		(pad "1" smd rect
			(at 1.4732 0)
			(size 1.1684 1.5748)
			(layers "B.Cu" "B.Mask" "B.Paste")
			(net "P52V_FAN_2")
		)
		(pad "2" smd rect
			(at -1.4732 0)
			(size 1.1684 1.5748)
			(layers "B.Cu" "B.Mask" "B.Paste")
			(net "GND")
		)
	)
)
